(kicad_pcb
	(version 20260206)
	(generator "pcbnew")
	(generator_version "10.0")
	(general
		(thickness 1.6)
		(legacy_teardrops no)
	)
	(paper "A4")
	(title_block
		(title "pdpb — Lightning_PDPB_BRD.brd")
		(comment 1 "Lightning (Wiwynn / Facebook NVMe JBOF) / footprints 697-703 of 1140")
	)
	(layers
		(0 "F.Cu" signal "TOP")
		(4 "In1.Cu" signal "L2GND")
		(6 "In2.Cu" signal "L3")
		(8 "In3.Cu" signal "L4VCC")
		(10 "In4.Cu" signal "L5VCC")
		(12 "In5.Cu" signal "L6")
		(14 "In6.Cu" signal "L7GND")
		(2 "B.Cu" signal "BOTTOM")
		(9 "F.Adhes" user "F.Adhesive")
		(11 "B.Adhes" user "B.Adhesive")
		(13 "F.Paste" user "Package Geometry/Pastemask Top")
		(15 "B.Paste" user "Package Geometry/Pastemask Bottom")
		(5 "F.SilkS" user "Ref Des/Silkscreen Top")
		(7 "B.SilkS" user "Ref Des/Silkscreen Bottom")
		(1 "F.Mask" user "Board Geometry/Soldermask Top")
		(3 "B.Mask" user "Board Geometry/Soldermask Bottom")
		(17 "Dwgs.User" user "User.Drawings")
		(19 "Cmts.User" user "User.Comments")
		(21 "Eco1.User" user "User.Eco1")
		(23 "Eco2.User" user "User.Eco2")
		(25 "Edge.Cuts" user "Board Geometry/Outline")
		(27 "Margin" user)
		(31 "F.CrtYd" user "Package Geometry/Place Bound Top")
		(29 "B.CrtYd" user "Package Geometry/Place Bound Bottom")
		(35 "F.Fab" user "Ref Des/Assembly Top")
		(33 "B.Fab" user "Ref Des/Assembly Bottom")
	)
	(footprint ""
		(layer "F.Cu")
		(at 49.149 -143.383 -90)
		(property "Reference" "R9900"
			(at 0 0 270)
			(layer "F.SilkS")
			(hide yes)
			(effects
				(font
					(size 1.27 1.27)
				)
			)
		)
		(property "Value" "1K82R2F-1-GP"
			(at 0.064008 -3.993896 270)
			(unlocked yes)
			(layer "F.Fab")
			(hide yes)
			(effects
				(font
					(size 1.016 1.016)
					(thickness 0.1524)
				)
			)
		)
		(property "Device Type" "R402H16"
			(at 0.064008 -5.517896 270)
			(unlocked yes)
			(layer "F.Fab")
			(hide yes)
			(effects
				(font
					(size 1.016 1.016)
					(thickness 0.1524)
				)
			)
		)
		(duplicate_pad_numbers_are_jumpers no)
		(fp_line
			(start -0.508 -0.9398)
			(end -0.508 0.9398)
			(stroke
				(width 0.1)
				(type default)
			)
			(layer "F.SilkS")
		)
		(fp_line
			(start 0.508 -0.9398)
			(end -0.508 -0.9398)
			(stroke
				(width 0.1)
				(type default)
			)
			(layer "F.SilkS")
		)
		(fp_rect
			(start -0.508 0.9398)
			(end 0.508 -0.9398)
			(stroke
				(width 0)
				(type default)
			)
			(fill no)
			(layer "F.CrtYd")
		)
		(fp_rect
			(start -0.508 0.9398)
			(end 0.508 -0.9398)
			(stroke
				(width 0)
				(type default)
			)
			(fill no)
			(layer "F.Fab")
		)
		(pad "1" smd custom
			(at 0 -0.4445 270)
			(size 0.1397 0.1397)
			(layers "F.Cu" "F.Mask" "F.Paste")
			(net "P12V")
			(options
				(clearance outline)
				(anchor circle)
			)
			(primitives
				(gr_poly
					(pts
						(arc
							(start -0.1778 -0.2794)
							(mid -0.249642 -0.249642)
							(end -0.2794 -0.1778)
						)
						(arc
							(start -0.2794 0.1778)
							(mid -0.249642 0.249642)
							(end -0.1778 0.2794)
						)
						(arc
							(start 0.1778 0.2794)
							(mid 0.249642 0.249642)
							(end 0.2794 0.1778)
						)
						(arc
							(start 0.2794 -0.1778)
							(mid 0.249642 -0.249642)
							(end 0.1778 -0.2794)
						)
					)
					(width 0)
					(fill yes)
				)
			)
		)
		(pad "2" smd custom
			(at 0 0.4445 270)
			(size 0.1397 0.1397)
			(layers "F.Cu" "F.Mask" "F.Paste")
			(net "DRV_ACT_8")
			(options
				(clearance outline)
				(anchor circle)
			)
			(primitives
				(gr_poly
					(pts
						(arc
							(start -0.1778 -0.2794)
							(mid -0.249642 -0.249642)
							(end -0.2794 -0.1778)
						)
						(arc
							(start -0.2794 0.1778)
							(mid -0.249642 0.249642)
							(end -0.1778 0.2794)
						)
						(arc
							(start 0.1778 0.2794)
							(mid 0.249642 0.249642)
							(end 0.2794 0.1778)
						)
						(arc
							(start 0.2794 -0.1778)
							(mid 0.249642 -0.249642)
							(end 0.1778 -0.2794)
						)
					)
					(width 0)
					(fill yes)
				)
			)
		)
	)
	(footprint ""
		(layer "F.Cu")
		(at 211.582 -461.518 -90)
		(property "Reference" "C341"
			(at 0 0 270)
			(layer "F.SilkS")
			(hide yes)
			(effects
				(font
					(size 1.27 1.27)
				)
			)
		)
		(property "Value" "SCD1U16V2KX-3GP"
			(at 1.1811 -2.7051 270)
			(unlocked yes)
			(layer "F.Fab")
			(hide yes)
			(effects
				(font
					(size 1.016 1.016)
					(thickness 0.1524)
				)
			)
		)
		(property "Device Type" "C402H22"
			(at 1.1811 -4.2291 270)
			(unlocked yes)
			(layer "F.Fab")
			(hide yes)
			(effects
				(font
					(size 1.016 1.016)
					(thickness 0.1524)
				)
			)
		)
		(duplicate_pad_numbers_are_jumpers no)
		(fp_rect
			(start -0.4318 0.9525)
			(end 0.4318 -0.9525)
			(stroke
				(width 0)
				(type default)
			)
			(fill no)
			(layer "F.CrtYd")
		)
		(fp_rect
			(start -0.4318 0.9525)
			(end 0.4318 -0.9525)
			(stroke
				(width 0)
				(type default)
			)
			(fill no)
			(layer "F.Fab")
		)
		(pad "1" smd custom
			(at 0 -0.4445 270)
			(size 0.1524 0.1524)
			(layers "F.Cu" "F.Mask" "F.Paste")
			(net "P3V3")
			(options
				(clearance outline)
				(anchor circle)
			)
			(primitives
				(gr_poly
					(pts
						(arc
							(start 0.3048 -0.2032)
							(mid 0.275042 -0.275042)
							(end 0.2032 -0.3048)
						)
						(arc
							(start -0.2032 -0.3048)
							(mid -0.275042 -0.275042)
							(end -0.3048 -0.2032)
						)
						(arc
							(start -0.3048 0.2032)
							(mid -0.275042 0.275042)
							(end -0.2032 0.3048)
						)
						(arc
							(start 0.2032 0.3048)
							(mid 0.275042 0.275042)
							(end 0.3048 0.2032)
						)
					)
					(width 0)
					(fill yes)
				)
			)
		)
		(pad "2" smd custom
			(at 0 0.4445 270)
			(size 0.1524 0.1524)
			(layers "F.Cu" "F.Mask" "F.Paste")
			(net "GND")
			(options
				(clearance outline)
				(anchor circle)
			)
			(primitives
				(gr_poly
					(pts
						(arc
							(start 0.3048 -0.2032)
							(mid 0.275042 -0.275042)
							(end 0.2032 -0.3048)
						)
						(arc
							(start -0.2032 -0.3048)
							(mid -0.275042 -0.275042)
							(end -0.3048 -0.2032)
						)
						(arc
							(start -0.3048 0.2032)
							(mid -0.275042 0.275042)
							(end -0.2032 0.3048)
						)
						(arc
							(start 0.2032 0.3048)
							(mid 0.275042 0.275042)
							(end 0.3048 0.2032)
						)
					)
					(width 0)
					(fill yes)
				)
			)
		)
	)
	(footprint ""
		(layer "F.Cu")
		(at 220.726 -344.039952)
		(property "Reference" "Q34"
			(at 0 0 0)
			(layer "F.SilkS")
			(hide yes)
			(effects
				(font
					(size 1.27 1.27)
				)
			)
		)
		(property "Value" "2N7002A-7-GP"
			(at 0.127 -8.9662 0)
			(unlocked yes)
			(layer "F.Fab")
			(hide yes)
			(effects
				(font
					(size 1.016 1.016)
					(thickness 0.1524)
				)
			)
		)
		(property "Device Type" "SOT23DGS2D4H48"
			(at 0.127 -10.4902 0)
			(unlocked yes)
			(layer "F.Fab")
			(hide yes)
			(effects
				(font
					(size 1.016 1.016)
					(thickness 0.1524)
				)
			)
		)
		(duplicate_pad_numbers_are_jumpers no)
		(fp_line
			(start -1.651 -1.778)
			(end -1.651 1.778)
			(stroke
				(width 0.1524)
				(type default)
			)
			(layer "F.SilkS")
		)
		(fp_line
			(start -1.651 1.778)
			(end 1.651 1.778)
			(stroke
				(width 0.1524)
				(type default)
			)
			(layer "F.SilkS")
		)
		(fp_line
			(start 1.651 -1.778)
			(end -1.651 -1.778)
			(stroke
				(width 0.1524)
				(type default)
			)
			(layer "F.SilkS")
		)
		(fp_line
			(start 1.651 1.778)
			(end 1.651 -1.778)
			(stroke
				(width 0.1524)
				(type default)
			)
			(layer "F.SilkS")
		)
		(fp_poly
			(pts
				(xy -1.778 1.8796) (xy -1.778 -1.8796) (xy 1.778 -1.8796) (xy 1.778 1.8796)
			)
			(stroke
				(width 0)
				(type default)
			)
			(fill no)
			(layer "F.CrtYd")
		)
		(fp_poly
			(pts
				(xy -1.778 1.8796) (xy -1.778 -1.8796) (xy 1.778 -1.8796) (xy 1.778 1.8796)
			)
			(stroke
				(width 0)
				(type default)
			)
			(fill no)
			(layer "F.Fab")
		)
		(pad "D" smd custom
			(at 0 -0.9525)
			(size 0.1905 0.1905)
			(layers "F.Cu" "F.Mask" "F.Paste")
			(net "SSD1_CLK0_OE_MOS_N")
			(options
				(clearance outline)
				(anchor circle)
			)
			(primitives
				(gr_poly
					(pts
						(arc
							(start -0.1778 0.5715)
							(mid -0.321484 0.511984)
							(end -0.381 0.3683)
						)
						(arc
							(start -0.381 -0.3683)
							(mid -0.321484 -0.511984)
							(end -0.1778 -0.5715)
						)
						(arc
							(start 0.1778 -0.5715)
							(mid 0.321484 -0.511984)
							(end 0.381 -0.3683)
						)
						(arc
							(start 0.381 0.3683)
							(mid 0.321484 0.511984)
							(end 0.1778 0.5715)
						)
					)
					(width 0)
					(fill yes)
				)
			)
		)
		(pad "G" smd custom
			(at -0.98425 0.9525)
			(size 0.1905 0.1905)
			(layers "F.Cu" "F.Mask" "F.Paste")
			(net "SSD1_CLK0_OE_R_N")
			(options
				(clearance outline)
				(anchor circle)
			)
			(primitives
				(gr_poly
					(pts
						(arc
							(start -0.1778 0.5715)
							(mid -0.321484 0.511984)
							(end -0.381 0.3683)
						)
						(arc
							(start -0.381 -0.3683)
							(mid -0.321484 -0.511984)
							(end -0.1778 -0.5715)
						)
						(arc
							(start 0.1778 -0.5715)
							(mid 0.321484 -0.511984)
							(end 0.381 -0.3683)
						)
						(arc
							(start 0.381 0.3683)
							(mid 0.321484 0.511984)
							(end 0.1778 0.5715)
						)
					)
					(width 0)
					(fill yes)
				)
			)
		)
		(pad "S" smd custom
			(at 0.98425 0.9525)
			(size 0.1905 0.1905)
			(layers "F.Cu" "F.Mask" "F.Paste")
			(net "GND")
			(options
				(clearance outline)
				(anchor circle)
			)
			(primitives
				(gr_poly
					(pts
						(arc
							(start -0.1778 0.5715)
							(mid -0.321484 0.511984)
							(end -0.381 0.3683)
						)
						(arc
							(start -0.381 -0.3683)
							(mid -0.321484 -0.511984)
							(end -0.1778 -0.5715)
						)
						(arc
							(start 0.1778 -0.5715)
							(mid 0.321484 -0.511984)
							(end 0.381 -0.3683)
						)
						(arc
							(start 0.381 0.3683)
							(mid 0.321484 0.511984)
							(end 0.1778 0.5715)
						)
					)
					(width 0)
					(fill yes)
				)
			)
		)
	)
	(footprint ""
		(layer "F.Cu")
		(at 53.594 -144.526 -90)
		(property "Reference" "R9837"
			(at 0 0 270)
			(layer "F.SilkS")
			(hide yes)
			(effects
				(font
					(size 1.27 1.27)
				)
			)
		)
		(property "Value" "0R2J-2-GP"
			(at 0.064008 -3.993896 270)
			(unlocked yes)
			(layer "F.Fab")
			(hide yes)
			(effects
				(font
					(size 1.016 1.016)
					(thickness 0.1524)
				)
			)
		)
		(property "Device Type" "R402H16"
			(at 0.064008 -5.517896 270)
			(unlocked yes)
			(layer "F.Fab")
			(hide yes)
			(effects
				(font
					(size 1.016 1.016)
					(thickness 0.1524)
				)
			)
		)
		(duplicate_pad_numbers_are_jumpers no)
		(fp_line
			(start -0.508 -0.9398)
			(end -0.508 0.9398)
			(stroke
				(width 0.1524)
				(type default)
			)
			(layer "F.SilkS")
		)
		(fp_line
			(start 0.508 -0.9398)
			(end -0.508 -0.9398)
			(stroke
				(width 0.1524)
				(type default)
			)
			(layer "F.SilkS")
		)
		(fp_rect
			(start -0.508 0.9398)
			(end 0.508 -0.9398)
			(stroke
				(width 0)
				(type default)
			)
			(fill no)
			(layer "F.CrtYd")
		)
		(fp_rect
			(start -0.508 0.9398)
			(end 0.508 -0.9398)
			(stroke
				(width 0)
				(type default)
			)
			(fill no)
			(layer "F.Fab")
		)
		(pad "1" smd custom
			(at 0 -0.4445 270)
			(size 0.1397 0.1397)
			(layers "F.Cu" "F.Mask" "F.Paste")
			(net "SSD_ACT_DR8_R")
			(options
				(clearance outline)
				(anchor circle)
			)
			(primitives
				(gr_poly
					(pts
						(arc
							(start -0.1778 -0.2794)
							(mid -0.249642 -0.249642)
							(end -0.2794 -0.1778)
						)
						(arc
							(start -0.2794 0.1778)
							(mid -0.249642 0.249642)
							(end -0.1778 0.2794)
						)
						(arc
							(start 0.1778 0.2794)
							(mid 0.249642 0.249642)
							(end 0.2794 0.1778)
						)
						(arc
							(start 0.2794 -0.1778)
							(mid 0.249642 -0.249642)
							(end 0.1778 -0.2794)
						)
					)
					(width 0)
					(fill yes)
				)
			)
		)
		(pad "2" smd custom
			(at 0 0.4445 270)
			(size 0.1397 0.1397)
			(layers "F.Cu" "F.Mask" "F.Paste")
			(net "SSD_ACT_DR8")
			(options
				(clearance outline)
				(anchor circle)
			)
			(primitives
				(gr_poly
					(pts
						(arc
							(start -0.1778 -0.2794)
							(mid -0.249642 -0.249642)
							(end -0.2794 -0.1778)
						)
						(arc
							(start -0.2794 0.1778)
							(mid -0.249642 0.249642)
							(end -0.1778 0.2794)
						)
						(arc
							(start 0.1778 0.2794)
							(mid 0.249642 0.249642)
							(end 0.2794 0.1778)
						)
						(arc
							(start 0.2794 -0.1778)
							(mid 0.249642 -0.249642)
							(end 0.1778 -0.2794)
						)
					)
					(width 0)
					(fill yes)
				)
			)
		)
	)
	(footprint ""
		(layer "F.Cu")
		(at 87.757 -116.586 90)
		(property "Reference" "R9587"
			(at 0 0 90)
			(layer "F.SilkS")
			(hide yes)
			(effects
				(font
					(size 1.27 1.27)
				)
			)
		)
		(property "Value" "4K7R2J-2-GP"
			(at 0.064008 -3.993896 90)
			(unlocked yes)
			(layer "F.Fab")
			(hide yes)
			(effects
				(font
					(size 1.016 1.016)
					(thickness 0.1524)
				)
			)
		)
		(property "Device Type" "R402H16"
			(at 0.064008 -5.517896 90)
			(unlocked yes)
			(layer "F.Fab")
			(hide yes)
			(effects
				(font
					(size 1.016 1.016)
					(thickness 0.1524)
				)
			)
		)
		(duplicate_pad_numbers_are_jumpers no)
		(fp_line
			(start 0.508 -0.9398)
			(end -0.508 -0.9398)
			(stroke
				(width 0.1524)
				(type default)
			)
			(layer "F.SilkS")
		)
		(fp_line
			(start -0.508 -0.9398)
			(end -0.508 0.9398)
			(stroke
				(width 0.1524)
				(type default)
			)
			(layer "F.SilkS")
		)
		(fp_rect
			(start -0.508 0.9398)
			(end 0.508 -0.9398)
			(stroke
				(width 0)
				(type default)
			)
			(fill no)
			(layer "F.CrtYd")
		)
		(fp_rect
			(start -0.508 0.9398)
			(end 0.508 -0.9398)
			(stroke
				(width 0)
				(type default)
			)
			(fill no)
			(layer "F.Fab")
		)
		(pad "1" smd custom
			(at 0 -0.4445 90)
			(size 0.1397 0.1397)
			(layers "F.Cu" "F.Mask" "F.Paste")
			(net "P3V3")
			(options
				(clearance outline)
				(anchor circle)
			)
			(primitives
				(gr_poly
					(pts
						(arc
							(start -0.1778 -0.2794)
							(mid -0.249642 -0.249642)
							(end -0.2794 -0.1778)
						)
						(arc
							(start -0.2794 0.1778)
							(mid -0.249642 0.249642)
							(end -0.1778 0.2794)
						)
						(arc
							(start 0.1778 0.2794)
							(mid 0.249642 0.249642)
							(end 0.2794 0.1778)
						)
						(arc
							(start 0.2794 -0.1778)
							(mid 0.249642 -0.249642)
							(end 0.1778 -0.2794)
						)
					)
					(width 0)
					(fill yes)
				)
			)
		)
		(pad "2" smd custom
			(at 0 0.4445 90)
			(size 0.1397 0.1397)
			(layers "F.Cu" "F.Mask" "F.Paste")
			(net "SSD13_CLK0_OE_N")
			(options
				(clearance outline)
				(anchor circle)
			)
			(primitives
				(gr_poly
					(pts
						(arc
							(start -0.1778 -0.2794)
							(mid -0.249642 -0.249642)
							(end -0.2794 -0.1778)
						)
						(arc
							(start -0.2794 0.1778)
							(mid -0.249642 0.249642)
							(end -0.1778 0.2794)
						)
						(arc
							(start 0.1778 0.2794)
							(mid 0.249642 0.249642)
							(end 0.2794 0.1778)
						)
						(arc
							(start 0.2794 -0.1778)
							(mid 0.249642 -0.249642)
							(end 0.1778 -0.2794)
						)
					)
					(width 0)
					(fill yes)
				)
			)
		)
	)
	(footprint ""
		(layer "F.Cu")
		(at 99.314 -110.236 180)
		(property "Reference" "R9131"
			(at 0 0 180)
			(layer "F.SilkS")
			(hide yes)
			(effects
				(font
					(size 1.27 1.27)
				)
			)
		)
		(property "Value" "27R2F-GP"
			(at 0.064008 -3.993896 180)
			(unlocked yes)
			(layer "F.Fab")
			(hide yes)
			(effects
				(font
					(size 1.016 1.016)
					(thickness 0.1524)
				)
			)
		)
		(property "Device Type" "R402H16"
			(at 0.064008 -5.517896 180)
			(unlocked yes)
			(layer "F.Fab")
			(hide yes)
			(effects
				(font
					(size 1.016 1.016)
					(thickness 0.1524)
				)
			)
		)
		(duplicate_pad_numbers_are_jumpers no)
		(fp_line
			(start 0.508 -0.9398)
			(end -0.508 -0.9398)
			(stroke
				(width 0.1524)
				(type default)
			)
			(layer "F.SilkS")
		)
		(fp_line
			(start -0.508 -0.9398)
			(end -0.508 0.9398)
			(stroke
				(width 0.1524)
				(type default)
			)
			(layer "F.SilkS")
		)
		(fp_rect
			(start -0.508 0.9398)
			(end 0.508 -0.9398)
			(stroke
				(width 0)
				(type default)
			)
			(fill no)
			(layer "F.CrtYd")
		)
		(fp_rect
			(start -0.508 0.9398)
			(end 0.508 -0.9398)
			(stroke
				(width 0)
				(type default)
			)
			(fill no)
			(layer "F.Fab")
		)
		(pad "1" smd custom
			(at 0 -0.4445 180)
			(size 0.1397 0.1397)
			(layers "F.Cu" "F.Mask" "F.Paste")
			(net "PE_CLK_100M_DR8_2_R_N")
			(options
				(clearance outline)
				(anchor circle)
			)
			(primitives
				(gr_poly
					(pts
						(arc
							(start -0.1778 -0.2794)
							(mid -0.249642 -0.249642)
							(end -0.2794 -0.1778)
						)
						(arc
							(start -0.2794 0.1778)
							(mid -0.249642 0.249642)
							(end -0.1778 0.2794)
						)
						(arc
							(start 0.1778 0.2794)
							(mid 0.249642 0.249642)
							(end 0.2794 0.1778)
						)
						(arc
							(start 0.2794 -0.1778)
							(mid 0.249642 -0.249642)
							(end 0.1778 -0.2794)
						)
					)
					(width 0)
					(fill yes)
				)
			)
		)
		(pad "2" smd custom
			(at 0 0.4445 180)
			(size 0.1397 0.1397)
			(layers "F.Cu" "F.Mask" "F.Paste")
			(net "PE_CLK100M_DR8_2_N")
			(options
				(clearance outline)
				(anchor circle)
			)
			(primitives
				(gr_poly
					(pts
						(arc
							(start -0.1778 -0.2794)
							(mid -0.249642 -0.249642)
							(end -0.2794 -0.1778)
						)
						(arc
							(start -0.2794 0.1778)
							(mid -0.249642 0.249642)
							(end -0.1778 0.2794)
						)
						(arc
							(start 0.1778 0.2794)
							(mid 0.249642 0.249642)
							(end 0.2794 0.1778)
						)
						(arc
							(start 0.2794 -0.1778)
							(mid 0.249642 -0.249642)
							(end 0.1778 -0.2794)
						)
					)
					(width 0)
					(fill yes)
				)
			)
		)
	)
	(footprint ""
		(layer "F.Cu")
		(at 33.01365 -102.35565)
		(property "Reference" "R9866"
			(at 0 0 0)
			(layer "F.SilkS")
			(hide yes)
			(effects
				(font
					(size 1.27 1.27)
				)
			)
		)
		(property "Value" "47KR2J-2-GP"
			(at 0.064008 -3.993896 0)
			(unlocked yes)
			(layer "F.Fab")
			(hide yes)
			(effects
				(font
					(size 1.016 1.016)
					(thickness 0.1524)
				)
			)
		)
		(property "Device Type" "R402H16"
			(at 0.064008 -5.517896 0)
			(unlocked yes)
			(layer "F.Fab")
			(hide yes)
			(effects
				(font
					(size 1.016 1.016)
					(thickness 0.1524)
				)
			)
		)
		(duplicate_pad_numbers_are_jumpers no)
		(fp_line
			(start -0.508 -0.9398)
			(end -0.508 0.9398)
			(stroke
				(width 0.1524)
				(type default)
			)
			(layer "F.SilkS")
		)
		(fp_line
			(start 0.508 -0.9398)
			(end -0.508 -0.9398)
			(stroke
				(width 0.1524)
				(type default)
			)
			(layer "F.SilkS")
		)
		(fp_rect
			(start -0.508 0.9398)
			(end 0.508 -0.9398)
			(stroke
				(width 0)
				(type default)
			)
			(fill no)
			(layer "F.CrtYd")
		)
		(fp_rect
			(start -0.508 0.9398)
			(end 0.508 -0.9398)
			(stroke
				(width 0)
				(type default)
			)
			(fill no)
			(layer "F.Fab")
		)
		(pad "1" smd custom
			(at 0 -0.4445)
			(size 0.1397 0.1397)
			(layers "F.Cu" "F.Mask" "F.Paste")
			(net "P12V")
			(options
				(clearance outline)
				(anchor circle)
			)
			(primitives
				(gr_poly
					(pts
						(arc
							(start -0.1778 -0.2794)
							(mid -0.249642 -0.249642)
							(end -0.2794 -0.1778)
						)
						(arc
							(start -0.2794 0.1778)
							(mid -0.249642 0.249642)
							(end -0.1778 0.2794)
						)
						(arc
							(start 0.1778 0.2794)
							(mid 0.249642 0.249642)
							(end 0.2794 0.1778)
						)
						(arc
							(start 0.2794 -0.1778)
							(mid 0.249642 -0.249642)
							(end 0.1778 -0.2794)
						)
					)
					(width 0)
					(fill yes)
				)
			)
		)
		(pad "2" smd custom
			(at 0 0.4445)
			(size 0.1397 0.1397)
			(layers "F.Cu" "F.Mask" "F.Paste")
			(net "P12V_MOST13_GATE")
			(options
				(clearance outline)
				(anchor circle)
			)
			(primitives
				(gr_poly
					(pts
						(arc
							(start -0.1778 -0.2794)
							(mid -0.249642 -0.249642)
							(end -0.2794 -0.1778)
						)
						(arc
							(start -0.2794 0.1778)
							(mid -0.249642 0.249642)
							(end -0.1778 0.2794)
						)
						(arc
							(start 0.1778 0.2794)
							(mid 0.249642 0.249642)
							(end 0.2794 0.1778)
						)
						(arc
							(start 0.2794 -0.1778)
							(mid 0.249642 -0.249642)
							(end 0.1778 -0.2794)
						)
					)
					(width 0)
					(fill yes)
				)
			)
		)
	)
)
